(kicad_pcb
	(version 20260206)
	(generator "pcbnew")
	(generator_version "10.0")
	(general
		(thickness 1.6)
		(legacy_teardrops no)
	)
	(paper "A4")
	(title_block
		(title "Wiwynn_Tioga_Pass_MB.brd")
		(comment 1 "Tioga Pass / footprints 1866-1873 of 4770")
	)
	(layers
		(0 "F.Cu" signal "TOP")
		(4 "In1.Cu" signal "L2GND")
		(6 "In2.Cu" signal "L3")
		(8 "In3.Cu" signal "L4GND")
		(10 "In4.Cu" signal "L5")
		(12 "In5.Cu" signal "L6GND")
		(14 "In6.Cu" signal "L7VCC")
		(16 "In7.Cu" signal "L8VCC")
		(18 "In8.Cu" signal "L9GND")
		(20 "In9.Cu" signal "L10")
		(22 "In10.Cu" signal "L11GND")
		(24 "In11.Cu" signal "L12")
		(26 "In12.Cu" signal "L13GND")
		(2 "B.Cu" signal "BOTTOM")
		(9 "F.Adhes" user "F.Adhesive")
		(11 "B.Adhes" user "B.Adhesive")
		(13 "F.Paste" user "Package Geometry/Pastemask Top")
		(15 "B.Paste" user "Package Geometry/Pastemask Bottom")
		(5 "F.SilkS" user "Ref Des/Silkscreen Top")
		(7 "B.SilkS" user "Ref Des/Silkscreen Bottom")
		(1 "F.Mask" user "Board Geometry/Soldermask Top")
		(3 "B.Mask" user "Board Geometry/Soldermask Bottom")
		(17 "Dwgs.User" user "User.Drawings")
		(19 "Cmts.User" user "User.Comments")
		(21 "Eco1.User" user "User.Eco1")
		(23 "Eco2.User" user "User.Eco2")
		(25 "Edge.Cuts" user "Board Geometry/Outline")
		(27 "Margin" user)
		(31 "F.CrtYd" user "Package Geometry/Place Bound Top")
		(29 "B.CrtYd" user "Package Geometry/Place Bound Bottom")
		(35 "F.Fab" user "Ref Des/Assembly Top")
		(33 "B.Fab" user "Ref Des/Assembly Bottom")
	)
	(footprint ""
		(layer "F.Cu")
		(at 202.079098 -69.316092 -90)
		(property "Reference" "RT26"
			(at 0 0 270)
			(layer "F.SilkS")
			(hide yes)
			(effects
				(font
					(size 1.27 1.27)
				)
			)
		)
		(property "Value" "*"
			(at -0.0254 -2.6289 270)
			(unlocked yes)
			(layer "F.Fab")
			(hide yes)
			(effects
				(font
					(size 1.27 1.016)
					(thickness 0.1524)
				)
			)
		)
		(property "Device Type" "1R3F-GP_RCL_GP-1R3F-GP,64.1R00A"
			(at -0.0254 -4.1529 270)
			(unlocked yes)
			(layer "F.Fab")
			(hide yes)
			(effects
				(font
					(size 1.27 1.016)
					(thickness 0.1524)
				)
			)
		)
		(duplicate_pad_numbers_are_jumpers no)
		(fp_line
			(start -0.4826 0)
			(end -0.2032 0)
			(stroke
				(width 0.2032)
				(type default)
			)
			(layer "F.SilkS")
		)
		(fp_line
			(start 0.2032 0)
			(end 0.4826 0)
			(stroke
				(width 0.2032)
				(type default)
			)
			(layer "F.SilkS")
		)
		(fp_rect
			(start -0.5842 1.3335)
			(end 0.5842 -1.3335)
			(stroke
				(width 0)
				(type default)
			)
			(fill no)
			(layer "F.CrtYd")
		)
		(fp_rect
			(start -0.5842 1.3335)
			(end 0.5842 -1.3335)
			(stroke
				(width 0)
				(type default)
			)
			(fill no)
			(layer "F.Fab")
		)
		(pad "1" smd custom
			(at 0 -0.762 270)
			(size 0.2159 0.2159)
			(layers "F.Cu" "F.Mask" "F.Paste")
			(net "VR_PVCCIN_CPU0_PHASE3_RC")
			(options
				(clearance outline)
				(anchor circle)
			)
			(primitives
				(gr_poly
					(pts
						(arc
							(start -0.3302 -0.4318)
							(mid -0.402042 -0.402042)
							(end -0.4318 -0.3302)
						)
						(arc
							(start -0.4318 0.3302)
							(mid -0.402042 0.402042)
							(end -0.3302 0.4318)
						)
						(arc
							(start 0.3302 0.4318)
							(mid 0.402042 0.402042)
							(end 0.4318 0.3302)
						)
						(arc
							(start 0.4318 -0.3302)
							(mid 0.402042 -0.402042)
							(end 0.3302 -0.4318)
						)
					)
					(width 0)
					(fill yes)
				)
			)
		)
		(pad "2" smd custom
			(at 0 0.762 270)
			(size 0.2159 0.2159)
			(layers "F.Cu" "F.Mask" "F.Paste")
			(net "GND")
			(options
				(clearance outline)
				(anchor circle)
			)
			(primitives
				(gr_poly
					(pts
						(arc
							(start -0.3302 -0.4318)
							(mid -0.402042 -0.402042)
							(end -0.4318 -0.3302)
						)
						(arc
							(start -0.4318 0.3302)
							(mid -0.402042 0.402042)
							(end -0.3302 0.4318)
						)
						(arc
							(start 0.3302 0.4318)
							(mid 0.402042 0.402042)
							(end 0.4318 0.3302)
						)
						(arc
							(start 0.4318 -0.3302)
							(mid 0.402042 -0.402042)
							(end 0.3302 -0.4318)
						)
					)
					(width 0)
					(fill yes)
				)
			)
		)
	)
	(footprint ""
		(layer "F.Cu")
		(at 409.928822 -11.436858)
		(property "Reference" "C8G9"
			(at 0 0 0)
			(layer "F.SilkS")
			(hide yes)
			(effects
				(font
					(size 1.27 1.27)
				)
			)
		)
		(property "Value" ""
			(at 0 0 0)
			(layer "F.Fab")
			(effects
				(font
					(size 1.27 1.27)
				)
			)
		)
		(duplicate_pad_numbers_are_jumpers no)
		(fp_rect
			(start -0.3048 0.9906)
			(end 0.3048 -0.1016)
			(stroke
				(width 0)
				(type default)
			)
			(fill no)
			(layer "F.CrtYd")
		)
		(fp_line
			(start -0.3048 -0.1016)
			(end -0.3048 0.9906)
			(stroke
				(width 0.1)
				(type default)
			)
			(layer "F.Fab")
		)
		(fp_line
			(start -0.3048 0.9906)
			(end 0.3048 0.9906)
			(stroke
				(width 0.1)
				(type default)
			)
			(layer "F.Fab")
		)
		(fp_line
			(start 0.3048 -0.1016)
			(end -0.3048 -0.1016)
			(stroke
				(width 0.1)
				(type default)
			)
			(layer "F.Fab")
		)
		(fp_line
			(start 0.3048 0.9906)
			(end 0.3048 -0.1016)
			(stroke
				(width 0.1)
				(type default)
			)
			(layer "F.Fab")
		)
		(pad "1" smd rect
			(at 0 0)
			(size 0.508 0.508)
			(layers "F.Cu" "F.Mask" "F.Paste")
			(net "P3E_CPU0_PE2_SS_TXP<0>")
		)
		(pad "2" smd rect
			(at 0 0.889)
			(size 0.508 0.508)
			(layers "F.Cu" "F.Mask" "F.Paste")
			(net "P3E_CPU0_PE2_SS_C_TXP<0>")
		)
		(zone
			(layer "F.Cu")
			(hatch none 0.5)
			(connect_pads
				(clearance 0)
			)
			(min_thickness 0.25)
			(keepout
				(tracks allowed)
				(vias not_allowed)
				(pads allowed)
				(copperpour not_allowed)
				(footprints allowed)
			)
			(placement
				(enabled no)
				(sheetname "")
			)
			(fill
				(thermal_gap 0.5)
				(thermal_bridge_width 0.5)
				(island_removal_mode 0)
			)
			(polygon
				(pts
					(xy 409.674822 -10.801858) (xy 410.182822 -10.801858) (xy 410.182822 -11.182858) (xy 409.674822 -11.182858)
				)
			)
		)
	)
	(footprint ""
		(layer "F.Cu")
		(at 467.90102 -35.052 -90)
		(property "Reference" "C9W19"
			(at 0.97536 0.76708 180)
			(unlocked yes)
			(layer "F.SilkS")
			(effects
				(font
					(size 0.4064 0.254)
					(thickness 0.1524)
				)
			)
		)
		(property "Value" ""
			(at 0 0 270)
			(layer "F.Fab")
			(effects
				(font
					(size 1.27 1.27)
				)
			)
		)
		(duplicate_pad_numbers_are_jumpers no)
		(fp_poly
			(pts
				(xy -0.4953 -0.2032) (xy 0.4953 -0.2032) (xy 0.4953 1.6002) (xy -0.4953 1.6002)
			)
			(stroke
				(width 0)
				(type default)
			)
			(fill no)
			(layer "F.CrtYd")
		)
		(fp_line
			(start -0.4953 1.6002)
			(end -0.4953 -0.2032)
			(stroke
				(width 0.1)
				(type default)
			)
			(layer "F.Fab")
		)
		(fp_line
			(start 0.4953 1.6002)
			(end -0.4953 1.6002)
			(stroke
				(width 0.1)
				(type default)
			)
			(layer "F.Fab")
		)
		(fp_line
			(start -0.4953 -0.2032)
			(end 0.4953 -0.2032)
			(stroke
				(width 0.1)
				(type default)
			)
			(layer "F.Fab")
		)
		(fp_line
			(start 0.4953 -0.2032)
			(end 0.4953 1.6002)
			(stroke
				(width 0.1)
				(type default)
			)
			(layer "F.Fab")
		)
		(pad "1" smd rect
			(at 0 0 270)
			(size 0.762 0.889)
			(layers "F.Cu" "F.Mask" "F.Paste")
			(net "P1V2_AUX_BMC")
		)
		(pad "2" smd rect
			(at 0 1.397 270)
			(size 0.762 0.889)
			(layers "F.Cu" "F.Mask" "F.Paste")
			(net "GND")
		)
		(zone
			(layer "F.Cu")
			(hatch none 0.5)
			(connect_pads
				(clearance 0)
			)
			(min_thickness 0.25)
			(keepout
				(tracks not_allowed)
				(vias allowed)
				(pads allowed)
				(copperpour not_allowed)
				(footprints allowed)
			)
			(placement
				(enabled no)
				(sheetname "")
			)
			(fill
				(thermal_gap 0.5)
				(thermal_bridge_width 0.5)
				(island_removal_mode 0)
			)
			(polygon
				(pts
					(xy 467.45652 -35.433) (xy 467.45652 -34.671) (xy 466.94852 -34.671) (xy 466.94852 -35.433)
				)
			)
		)
	)
	(footprint ""
		(layer "F.Cu")
		(at 259.4356 -3.321812 90)
		(property "Reference" "C5G20"
			(at 0 0 90)
			(layer "F.SilkS")
			(hide yes)
			(effects
				(font
					(size 1.27 1.27)
				)
			)
		)
		(property "Value" ""
			(at 0 0 90)
			(layer "F.Fab")
			(effects
				(font
					(size 1.27 1.27)
				)
			)
		)
		(duplicate_pad_numbers_are_jumpers no)
		(fp_rect
			(start -0.7239 -0.2159)
			(end 0.7239 1.9939)
			(stroke
				(width 0)
				(type default)
			)
			(fill no)
			(layer "F.CrtYd")
		)
		(fp_line
			(start 0.7239 -0.2159)
			(end -0.7239 -0.2159)
			(stroke
				(width 0.1)
				(type default)
			)
			(layer "F.Fab")
		)
		(fp_line
			(start -0.7239 -0.2159)
			(end -0.7239 1.9939)
			(stroke
				(width 0.1)
				(type default)
			)
			(layer "F.Fab")
		)
		(fp_line
			(start 0.7239 1.9939)
			(end 0.7239 -0.2159)
			(stroke
				(width 0.1)
				(type default)
			)
			(layer "F.Fab")
		)
		(fp_line
			(start -0.7239 1.9939)
			(end 0.7239 1.9939)
			(stroke
				(width 0.1)
				(type default)
			)
			(layer "F.Fab")
		)
		(pad "1" smd rect
			(at 0 0 90)
			(size 1.27 1.016)
			(layers "F.Cu" "F.Mask" "F.Paste")
			(net "PVDDQ_ABC")
		)
		(pad "2" smd rect
			(at 0 1.778 90)
			(size 1.27 1.016)
			(layers "F.Cu" "F.Mask" "F.Paste")
			(net "GND")
		)
		(zone
			(layer "F.Cu")
			(hatch none 0.5)
			(connect_pads
				(clearance 0)
			)
			(min_thickness 0.25)
			(keepout
				(tracks not_allowed)
				(vias allowed)
				(pads allowed)
				(copperpour not_allowed)
				(footprints allowed)
			)
			(placement
				(enabled no)
				(sheetname "")
			)
			(fill
				(thermal_gap 0.5)
				(thermal_bridge_width 0.5)
				(island_removal_mode 0)
			)
			(polygon
				(pts
					(xy 259.9436 -2.686812) (xy 260.7056 -2.686812) (xy 260.7056 -3.956812) (xy 259.9436 -3.956812)
				)
			)
		)
	)
	(footprint ""
		(layer "F.Cu")
		(at 193.675 -3.7465)
		(property "Reference" "R4G21"
			(at 0 0 0)
			(layer "F.SilkS")
			(hide yes)
			(effects
				(font
					(size 1.27 1.27)
				)
			)
		)
		(property "Value" ""
			(at 0 0 0)
			(layer "F.Fab")
			(effects
				(font
					(size 1.27 1.27)
				)
			)
		)
		(duplicate_pad_numbers_are_jumpers no)
		(fp_poly
			(pts
				(xy -0.2794 -0.1016) (xy 0.2794 -0.1016) (xy 0.2794 0.9906) (xy -0.2794 0.9906)
			)
			(stroke
				(width 0)
				(type default)
			)
			(fill no)
			(layer "F.CrtYd")
		)
		(fp_line
			(start -0.2794 -0.1016)
			(end -0.2794 0.9906)
			(stroke
				(width 0.1)
				(type default)
			)
			(layer "F.Fab")
		)
		(fp_line
			(start -0.2794 0.9906)
			(end 0.2794 0.9906)
			(stroke
				(width 0.1)
				(type default)
			)
			(layer "F.Fab")
		)
		(fp_line
			(start 0.2794 -0.1016)
			(end -0.2794 -0.1016)
			(stroke
				(width 0.1)
				(type default)
			)
			(layer "F.Fab")
		)
		(fp_line
			(start 0.2794 0.9906)
			(end 0.2794 -0.1016)
			(stroke
				(width 0.1)
				(type default)
			)
			(layer "F.Fab")
		)
		(pad "1" smd rect
			(at 0 0)
			(size 0.508 0.508)
			(layers "F.Cu" "F.Mask" "F.Paste")
			(net "PVDDQ_ABC")
		)
		(pad "2" smd rect
			(at 0 0.889)
			(size 0.508 0.508)
			(layers "F.Cu" "F.Mask" "F.Paste")
			(net "M_C_VREF")
		)
		(zone
			(layer "F.Cu")
			(hatch none 0.5)
			(connect_pads
				(clearance 0)
			)
			(min_thickness 0.25)
			(keepout
				(tracks allowed)
				(vias not_allowed)
				(pads allowed)
				(copperpour not_allowed)
				(footprints allowed)
			)
			(placement
				(enabled no)
				(sheetname "")
			)
			(fill
				(thermal_gap 0.5)
				(thermal_bridge_width 0.5)
				(island_removal_mode 0)
			)
			(polygon
				(pts
					(xy 193.421 -3.4925) (xy 193.929 -3.4925) (xy 193.929 -3.1115) (xy 193.421 -3.1115)
				)
			)
		)
		(zone
			(layer "F.Cu")
			(hatch none 0.5)
			(connect_pads
				(clearance 0)
			)
			(min_thickness 0.25)
			(keepout
				(tracks not_allowed)
				(vias allowed)
				(pads allowed)
				(copperpour not_allowed)
				(footprints allowed)
			)
			(placement
				(enabled no)
				(sheetname "")
			)
			(fill
				(thermal_gap 0.5)
				(thermal_bridge_width 0.5)
				(island_removal_mode 0)
			)
			(polygon
				(pts
					(xy 193.421 -3.1115) (xy 193.929 -3.1115) (xy 193.929 -3.4925) (xy 193.421 -3.4925)
				)
			)
		)
	)
	(footprint ""
		(layer "F.Cu")
		(at 214.8586 -94.4372)
		(property "Reference" "C4C11"
			(at 0.97536 0.76708 270)
			(unlocked yes)
			(layer "F.SilkS")
			(effects
				(font
					(size 0.4064 0.254)
					(thickness 0.1524)
				)
			)
		)
		(property "Value" ""
			(at 0 0 0)
			(layer "F.Fab")
			(effects
				(font
					(size 1.27 1.27)
				)
			)
		)
		(duplicate_pad_numbers_are_jumpers no)
		(fp_poly
			(pts
				(xy -0.4953 -0.2032) (xy 0.4953 -0.2032) (xy 0.4953 1.6002) (xy -0.4953 1.6002)
			)
			(stroke
				(width 0)
				(type default)
			)
			(fill no)
			(layer "F.CrtYd")
		)
		(fp_line
			(start -0.4953 -0.2032)
			(end 0.4953 -0.2032)
			(stroke
				(width 0.1)
				(type default)
			)
			(layer "F.Fab")
		)
		(fp_line
			(start -0.4953 1.6002)
			(end -0.4953 -0.2032)
			(stroke
				(width 0.1)
				(type default)
			)
			(layer "F.Fab")
		)
		(fp_line
			(start 0.4953 -0.2032)
			(end 0.4953 1.6002)
			(stroke
				(width 0.1)
				(type default)
			)
			(layer "F.Fab")
		)
		(fp_line
			(start 0.4953 1.6002)
			(end -0.4953 1.6002)
			(stroke
				(width 0.1)
				(type default)
			)
			(layer "F.Fab")
		)
		(pad "1" smd rect
			(at 0 0)
			(size 0.762 0.889)
			(layers "F.Cu" "F.Mask" "F.Paste")
			(net "PVSA_CPU0")
		)
		(pad "2" smd rect
			(at 0 1.397)
			(size 0.762 0.889)
			(layers "F.Cu" "F.Mask" "F.Paste")
			(net "GND")
		)
		(zone
			(layer "F.Cu")
			(hatch none 0.5)
			(connect_pads
				(clearance 0)
			)
			(min_thickness 0.25)
			(keepout
				(tracks not_allowed)
				(vias allowed)
				(pads allowed)
				(copperpour not_allowed)
				(footprints allowed)
			)
			(placement
				(enabled no)
				(sheetname "")
			)
			(fill
				(thermal_gap 0.5)
				(thermal_bridge_width 0.5)
				(island_removal_mode 0)
			)
			(polygon
				(pts
					(xy 214.4776 -93.9927) (xy 215.2396 -93.9927) (xy 215.2396 -93.4847) (xy 214.4776 -93.4847)
				)
			)
		)
	)
	(footprint ""
		(layer "F.Cu")
		(at 175.88738 -73.69556 180)
		(property "Reference" "R4D38"
			(at 0 0 180)
			(layer "F.SilkS")
			(hide yes)
			(effects
				(font
					(size 1.27 1.27)
				)
			)
		)
		(property "Value" ""
			(at 0 0 180)
			(layer "F.Fab")
			(effects
				(font
					(size 1.27 1.27)
				)
			)
		)
		(duplicate_pad_numbers_are_jumpers no)
		(fp_poly
			(pts
				(xy -0.2794 -0.1016) (xy 0.2794 -0.1016) (xy 0.2794 0.9906) (xy -0.2794 0.9906)
			)
			(stroke
				(width 0)
				(type default)
			)
			(fill no)
			(layer "F.CrtYd")
		)
		(fp_line
			(start 0.2794 0.9906)
			(end 0.2794 -0.1016)
			(stroke
				(width 0.1)
				(type default)
			)
			(layer "F.Fab")
		)
		(fp_line
			(start 0.2794 -0.1016)
			(end -0.2794 -0.1016)
			(stroke
				(width 0.1)
				(type default)
			)
			(layer "F.Fab")
		)
		(fp_line
			(start -0.2794 0.9906)
			(end 0.2794 0.9906)
			(stroke
				(width 0.1)
				(type default)
			)
			(layer "F.Fab")
		)
		(fp_line
			(start -0.2794 -0.1016)
			(end -0.2794 0.9906)
			(stroke
				(width 0.1)
				(type default)
			)
			(layer "F.Fab")
		)
		(pad "1" smd rect
			(at 0 0 180)
			(size 0.508 0.508)
			(layers "F.Cu" "F.Mask" "F.Paste")
			(net "P3V3_DB1200")
		)
		(pad "2" smd rect
			(at 0 0.889 180)
			(size 0.508 0.508)
			(layers "F.Cu" "F.Mask" "F.Paste")
			(net "FM_DB1200_SMB_SA1")
		)
		(zone
			(layer "F.Cu")
			(hatch none 0.5)
			(connect_pads
				(clearance 0)
			)
			(min_thickness 0.25)
			(keepout
				(tracks not_allowed)
				(vias allowed)
				(pads allowed)
				(copperpour not_allowed)
				(footprints allowed)
			)
			(placement
				(enabled no)
				(sheetname "")
			)
			(fill
				(thermal_gap 0.5)
				(thermal_bridge_width 0.5)
				(island_removal_mode 0)
			)
			(polygon
				(pts
					(xy 176.14138 -74.33056) (xy 175.63338 -74.33056) (xy 175.63338 -73.94956) (xy 176.14138 -73.94956)
				)
			)
		)
		(zone
			(layer "F.Cu")
			(hatch none 0.5)
			(connect_pads
				(clearance 0)
			)
			(min_thickness 0.25)
			(keepout
				(tracks allowed)
				(vias not_allowed)
				(pads allowed)
				(copperpour not_allowed)
				(footprints allowed)
			)
			(placement
				(enabled no)
				(sheetname "")
			)
			(fill
				(thermal_gap 0.5)
				(thermal_bridge_width 0.5)
				(island_removal_mode 0)
			)
			(polygon
				(pts
					(xy 176.14138 -73.94956) (xy 175.63338 -73.94956) (xy 175.63338 -74.33056) (xy 176.14138 -74.33056)
				)
			)
		)
	)
	(footprint ""
		(layer "F.Cu")
		(at 410.69006 -101.49332)
		(property "Reference" "R7W16"
			(at -0.8382 -0.67818 0)
			(unlocked yes)
			(layer "F.SilkS")
			(effects
				(font
					(size 0.4064 0.254)
					(thickness 0.1524)
				)
				(justify left)
			)
		)
		(property "Value" ""
			(at 0 0 0)
			(layer "F.Fab")
			(effects
				(font
					(size 1.27 1.27)
				)
			)
		)
		(duplicate_pad_numbers_are_jumpers no)
		(fp_poly
			(pts
				(xy -0.2794 -0.1016) (xy 0.2794 -0.1016) (xy 0.2794 0.9906) (xy -0.2794 0.9906)
			)
			(stroke
				(width 0)
				(type default)
			)
			(fill no)
			(layer "F.CrtYd")
		)
		(fp_line
			(start -0.2794 -0.1016)
			(end -0.2794 0.9906)
			(stroke
				(width 0.1)
				(type default)
			)
			(layer "F.Fab")
		)
		(fp_line
			(start -0.2794 0.9906)
			(end 0.2794 0.9906)
			(stroke
				(width 0.1)
				(type default)
			)
			(layer "F.Fab")
		)
		(fp_line
			(start 0.2794 -0.1016)
			(end -0.2794 -0.1016)
			(stroke
				(width 0.1)
				(type default)
			)
			(layer "F.Fab")
		)
		(fp_line
			(start 0.2794 0.9906)
			(end 0.2794 -0.1016)
			(stroke
				(width 0.1)
				(type default)
			)
			(layer "F.Fab")
		)
		(pad "1" smd rect
			(at 0 0)
			(size 0.508 0.508)
			(layers "F.Cu" "F.Mask" "F.Paste")
			(net "IRQ_DIMM_SAVE_LVT3_R_N")
		)
		(pad "2" smd rect
			(at 0 0.889)
			(size 0.508 0.508)
			(layers "F.Cu" "F.Mask" "F.Paste")
			(net "IRQ_DIMM_SAVE_LVT3_N")
		)
		(zone
			(layer "F.Cu")
			(hatch none 0.5)
			(connect_pads
				(clearance 0)
			)
			(min_thickness 0.25)
			(keepout
				(tracks allowed)
				(vias not_allowed)
				(pads allowed)
				(copperpour not_allowed)
				(footprints allowed)
			)
			(placement
				(enabled no)
				(sheetname "")
			)
			(fill
				(thermal_gap 0.5)
				(thermal_bridge_width 0.5)
				(island_removal_mode 0)
			)
			(polygon
				(pts
					(xy 410.43606 -101.23932) (xy 410.94406 -101.23932) (xy 410.94406 -100.85832) (xy 410.43606 -100.85832)
				)
			)
		)
		(zone
			(layer "F.Cu")
			(hatch none 0.5)
			(connect_pads
				(clearance 0)
			)
			(min_thickness 0.25)
			(keepout
				(tracks not_allowed)
				(vias allowed)
				(pads allowed)
				(copperpour not_allowed)
				(footprints allowed)
			)
			(placement
				(enabled no)
				(sheetname "")
			)
			(fill
				(thermal_gap 0.5)
				(thermal_bridge_width 0.5)
				(island_removal_mode 0)
			)
			(polygon
				(pts
					(xy 410.43606 -100.85832) (xy 410.94406 -100.85832) (xy 410.94406 -101.23932) (xy 410.43606 -101.23932)
				)
			)
		)
	)
)
